(kicad_pcb
	(version 20260206)
	(generator "pcbnew")
	(generator_version "10.0")
	(general
		(thickness 1.6)
		(legacy_teardrops no)
	)
	(paper "A4")
	(title_block
		(title "Bryce Canyon_IOM_M2_16342-2_OCP.brd")
		(comment 1 "Bryce Canyon / footprints 70-75 of 1146")
	)
	(layers
		(0 "F.Cu" signal "TOP")
		(4 "In1.Cu" signal "L2GND")
		(6 "In2.Cu" signal "L3")
		(8 "In3.Cu" signal "L4VCC")
		(10 "In4.Cu" signal "L5VCC")
		(12 "In5.Cu" signal "L6")
		(14 "In6.Cu" signal "L7GND")
		(2 "B.Cu" signal "BOTTOM")
		(9 "F.Adhes" user "F.Adhesive")
		(11 "B.Adhes" user "B.Adhesive")
		(13 "F.Paste" user "Package Geometry/Pastemask Top")
		(15 "B.Paste" user "Package Geometry/Pastemask Bottom")
		(5 "F.SilkS" user "Ref Des/Silkscreen Top")
		(7 "B.SilkS" user "Ref Des/Silkscreen Bottom")
		(1 "F.Mask" user "Board Geometry/Soldermask Top")
		(3 "B.Mask" user "Board Geometry/Soldermask Bottom")
		(17 "Dwgs.User" user "User.Drawings")
		(19 "Cmts.User" user "User.Comments")
		(21 "Eco1.User" user "User.Eco1")
		(23 "Eco2.User" user "User.Eco2")
		(25 "Edge.Cuts" user "Board Geometry/Outline")
		(27 "Margin" user)
		(31 "F.CrtYd" user "Package Geometry/Place Bound Top")
		(29 "B.CrtYd" user "Package Geometry/Place Bound Bottom")
		(35 "F.Fab" user "Ref Des/Assembly Top")
		(33 "B.Fab" user "Ref Des/Assembly Bottom")
	)
	(footprint ""
		(layer "F.Cu")
		(at 68.686426 -145.913348 90)
		(property "Reference" "R763"
			(at 0 0 90)
			(layer "F.SilkS")
			(hide yes)
			(effects
				(font
					(size 1.27 1.27)
				)
			)
		)
		(property "Value" "33R2J-2-GP"
			(at 0.064008 -3.993896 90)
			(unlocked yes)
			(layer "F.Fab")
			(hide yes)
			(effects
				(font
					(size 1.016 1.016)
					(thickness 0.1524)
				)
			)
		)
		(property "Device Type" "R402H16"
			(at 0.064008 -5.517896 90)
			(unlocked yes)
			(layer "F.Fab")
			(hide yes)
			(effects
				(font
					(size 1.016 1.016)
					(thickness 0.1524)
				)
			)
		)
		(duplicate_pad_numbers_are_jumpers no)
		(fp_line
			(start 0.508 -0.9398)
			(end -0.508 -0.9398)
			(stroke
				(width 0.1524)
				(type default)
			)
			(layer "F.SilkS")
		)
		(fp_line
			(start -0.508 -0.9398)
			(end -0.508 0.9398)
			(stroke
				(width 0.1524)
				(type default)
			)
			(layer "F.SilkS")
		)
		(fp_rect
			(start -0.508 0.9398)
			(end 0.508 -0.9398)
			(stroke
				(width 0)
				(type default)
			)
			(fill no)
			(layer "F.CrtYd")
		)
		(fp_rect
			(start -0.508 0.9398)
			(end 0.508 -0.9398)
			(stroke
				(width 0)
				(type default)
			)
			(fill no)
			(layer "F.Fab")
		)
		(pad "1" smd custom
			(at 0 -0.4445 90)
			(size 0.1397 0.1397)
			(layers "F.Cu" "F.Mask" "F.Paste")
			(net "NCSI_RCLK_R")
			(options
				(clearance outline)
				(anchor circle)
			)
			(primitives
				(gr_poly
					(pts
						(arc
							(start -0.1778 -0.2794)
							(mid -0.249642 -0.249642)
							(end -0.2794 -0.1778)
						)
						(arc
							(start -0.2794 0.1778)
							(mid -0.249642 0.249642)
							(end -0.1778 0.2794)
						)
						(arc
							(start 0.1778 0.2794)
							(mid 0.249642 0.249642)
							(end 0.2794 0.1778)
						)
						(arc
							(start 0.2794 -0.1778)
							(mid 0.249642 -0.249642)
							(end 0.1778 -0.2794)
						)
					)
					(width 0)
					(fill yes)
				)
			)
		)
		(pad "2" smd custom
			(at 0 0.4445 90)
			(size 0.1397 0.1397)
			(layers "F.Cu" "F.Mask" "F.Paste")
			(net "NCSI_RCLK")
			(options
				(clearance outline)
				(anchor circle)
			)
			(primitives
				(gr_poly
					(pts
						(arc
							(start -0.1778 -0.2794)
							(mid -0.249642 -0.249642)
							(end -0.2794 -0.1778)
						)
						(arc
							(start -0.2794 0.1778)
							(mid -0.249642 0.249642)
							(end -0.1778 0.2794)
						)
						(arc
							(start 0.1778 0.2794)
							(mid 0.249642 0.249642)
							(end 0.2794 0.1778)
						)
						(arc
							(start 0.2794 -0.1778)
							(mid 0.249642 -0.249642)
							(end 0.1778 -0.2794)
						)
					)
					(width 0)
					(fill yes)
				)
			)
		)
	)
	(footprint ""
		(layer "F.Cu")
		(at 75.946 -167.5892)
		(property "Reference" "R539"
			(at 0 0 0)
			(layer "F.SilkS")
			(hide yes)
			(effects
				(font
					(size 1.27 1.27)
				)
			)
		)
		(property "Value" "10KR2F-2-GP"
			(at 0.064008 -3.993896 0)
			(unlocked yes)
			(layer "F.Fab")
			(hide yes)
			(effects
				(font
					(size 1.016 1.016)
					(thickness 0.1524)
				)
			)
		)
		(property "Device Type" "R402H16"
			(at 0.064008 -5.517896 0)
			(unlocked yes)
			(layer "F.Fab")
			(hide yes)
			(effects
				(font
					(size 1.016 1.016)
					(thickness 0.1524)
				)
			)
		)
		(duplicate_pad_numbers_are_jumpers no)
		(fp_line
			(start -0.508 -0.9398)
			(end -0.508 0.9398)
			(stroke
				(width 0.1524)
				(type default)
			)
			(layer "F.SilkS")
		)
		(fp_line
			(start 0.508 -0.9398)
			(end -0.508 -0.9398)
			(stroke
				(width 0.1524)
				(type default)
			)
			(layer "F.SilkS")
		)
		(fp_rect
			(start -0.508 0.9398)
			(end 0.508 -0.9398)
			(stroke
				(width 0)
				(type default)
			)
			(fill no)
			(layer "F.CrtYd")
		)
		(fp_rect
			(start -0.508 0.9398)
			(end 0.508 -0.9398)
			(stroke
				(width 0)
				(type default)
			)
			(fill no)
			(layer "F.Fab")
		)
		(pad "1" smd custom
			(at 0 -0.4445)
			(size 0.1397 0.1397)
			(layers "F.Cu" "F.Mask" "F.Paste")
			(net "P3V3_STBY")
			(options
				(clearance outline)
				(anchor circle)
			)
			(primitives
				(gr_poly
					(pts
						(arc
							(start -0.1778 -0.2794)
							(mid -0.249642 -0.249642)
							(end -0.2794 -0.1778)
						)
						(arc
							(start -0.2794 0.1778)
							(mid -0.249642 0.249642)
							(end -0.1778 0.2794)
						)
						(arc
							(start 0.1778 0.2794)
							(mid 0.249642 0.249642)
							(end 0.2794 0.1778)
						)
						(arc
							(start 0.2794 -0.1778)
							(mid 0.249642 -0.249642)
							(end 0.1778 -0.2794)
						)
					)
					(width 0)
					(fill yes)
				)
			)
		)
		(pad "2" smd custom
			(at 0 0.4445)
			(size 0.1397 0.1397)
			(layers "F.Cu" "F.Mask" "F.Paste")
			(net "P1V15_STBY_PG")
			(options
				(clearance outline)
				(anchor circle)
			)
			(primitives
				(gr_poly
					(pts
						(arc
							(start -0.1778 -0.2794)
							(mid -0.249642 -0.249642)
							(end -0.2794 -0.1778)
						)
						(arc
							(start -0.2794 0.1778)
							(mid -0.249642 0.249642)
							(end -0.1778 0.2794)
						)
						(arc
							(start 0.1778 0.2794)
							(mid 0.249642 0.249642)
							(end 0.2794 0.1778)
						)
						(arc
							(start 0.2794 -0.1778)
							(mid 0.249642 -0.249642)
							(end 0.1778 -0.2794)
						)
					)
					(width 0)
					(fill yes)
				)
			)
		)
	)
	(footprint ""
		(layer "F.Cu")
		(at 80.140048 -150.060914 90)
		(property "Reference" "U102"
			(at 0 0 90)
			(layer "F.SilkS")
			(hide yes)
			(effects
				(font
					(size 1.27 1.27)
				)
			)
		)
		(property "Value" "SN74LVC1G14DCKR-GP"
			(at -2.3368 -8.6868 90)
			(unlocked yes)
			(layer "F.Fab")
			(hide yes)
			(effects
				(font
					(size 1.016 1.016)
					(thickness 0.1524)
				)
			)
		)
		(property "Device Type" "SC70-5H44"
			(at -2.3114 -10.414 90)
			(unlocked yes)
			(layer "F.Fab")
			(hide yes)
			(effects
				(font
					(size 1.016 1.016)
					(thickness 0.1524)
				)
			)
		)
		(duplicate_pad_numbers_are_jumpers no)
		(fp_line
			(start 1.3843 -1.8034)
			(end 1.3843 -1.1176)
			(stroke
				(width 0.3302)
				(type default)
			)
			(layer "F.SilkS")
		)
		(fp_line
			(start 0.6604 -1.8034)
			(end 1.3843 -1.8034)
			(stroke
				(width 0.3302)
				(type default)
			)
			(layer "F.SilkS")
		)
		(fp_line
			(start 1.27 -1.7018)
			(end 1.27 1.7018)
			(stroke
				(width 0.1524)
				(type default)
			)
			(layer "F.SilkS")
		)
		(fp_line
			(start -1.27 -1.7018)
			(end 1.27 -1.7018)
			(stroke
				(width 0.1524)
				(type default)
			)
			(layer "F.SilkS")
		)
		(fp_line
			(start 1.27 1.7018)
			(end -1.27 1.7018)
			(stroke
				(width 0.1524)
				(type default)
			)
			(layer "F.SilkS")
		)
		(fp_line
			(start -1.27 1.7018)
			(end -1.27 -1.7018)
			(stroke
				(width 0.1524)
				(type default)
			)
			(layer "F.SilkS")
		)
		(fp_rect
			(start -1.524 1.9558)
			(end 1.524 -1.9558)
			(stroke
				(width 0)
				(type default)
			)
			(fill no)
			(layer "F.CrtYd")
		)
		(fp_poly
			(pts
				(xy -1.524 -1.9558) (xy 1.524 -1.9558) (xy 1.524 1.9558) (xy -1.524 1.9558)
			)
			(stroke
				(width 0)
				(type default)
			)
			(fill no)
			(layer "F.Fab")
		)
		(pad "1" smd rect
			(at 0.65024 -0.8255 90)
			(size 0.4064 1.2192)
			(layers "F.Cu" "F.Mask" "F.Paste")
			(net "Net_44")
		)
		(pad "2" smd rect
			(at 0 -0.8255 90)
			(size 0.4064 1.2192)
			(layers "F.Cu" "F.Mask" "F.Paste")
			(net "COMP_TO_BMC_RESET_R")
		)
		(pad "3" smd rect
			(at -0.65024 -0.8255 90)
			(size 0.4064 1.2192)
			(layers "F.Cu" "F.Mask" "F.Paste")
			(net "GND")
		)
		(pad "4" smd rect
			(at -0.65024 0.8255 90)
			(size 0.4064 1.2192)
			(layers "F.Cu" "F.Mask" "F.Paste")
			(net "COMP_TO_BMC_RESET_N_OUT")
		)
		(pad "5" smd rect
			(at 0.65024 0.8255 90)
			(size 0.4064 1.2192)
			(layers "F.Cu" "F.Mask" "F.Paste")
			(net "P3V3_STBY")
		)
	)
	(footprint ""
		(layer "F.Cu")
		(at 132.918454 -13.372846)
		(property "Reference" "C134"
			(at 0 0 0)
			(layer "F.SilkS")
			(hide yes)
			(effects
				(font
					(size 1.27 1.27)
				)
			)
		)
		(property "Value" "SCD015U25V2KX-GP"
			(at 1.1811 -2.7051 0)
			(unlocked yes)
			(layer "F.Fab")
			(hide yes)
			(effects
				(font
					(size 1.016 1.016)
					(thickness 0.1524)
				)
			)
		)
		(property "Device Type" "C402H22"
			(at 1.1811 -4.2291 0)
			(unlocked yes)
			(layer "F.Fab")
			(hide yes)
			(effects
				(font
					(size 1.016 1.016)
					(thickness 0.1524)
				)
			)
		)
		(duplicate_pad_numbers_are_jumpers no)
		(fp_rect
			(start -0.4318 0.9525)
			(end 0.4318 -0.9525)
			(stroke
				(width 0)
				(type default)
			)
			(fill no)
			(layer "F.CrtYd")
		)
		(fp_rect
			(start -0.4318 0.9525)
			(end 0.4318 -0.9525)
			(stroke
				(width 0)
				(type default)
			)
			(fill no)
			(layer "F.Fab")
		)
		(pad "1" smd custom
			(at 0 -0.4445)
			(size 0.1524 0.1524)
			(layers "F.Cu" "F.Mask" "F.Paste")
			(net "ADM1278_HS_P")
			(options
				(clearance outline)
				(anchor circle)
			)
			(primitives
				(gr_poly
					(pts
						(arc
							(start 0.3048 -0.2032)
							(mid 0.275042 -0.275042)
							(end 0.2032 -0.3048)
						)
						(arc
							(start -0.2032 -0.3048)
							(mid -0.275042 -0.275042)
							(end -0.3048 -0.2032)
						)
						(arc
							(start -0.3048 0.2032)
							(mid -0.275042 0.275042)
							(end -0.2032 0.3048)
						)
						(arc
							(start 0.2032 0.3048)
							(mid 0.275042 0.275042)
							(end 0.3048 0.2032)
						)
					)
					(width 0)
					(fill yes)
				)
			)
		)
		(pad "2" smd custom
			(at 0 0.4445)
			(size 0.1524 0.1524)
			(layers "F.Cu" "F.Mask" "F.Paste")
			(net "ADM1278_HS_N")
			(options
				(clearance outline)
				(anchor circle)
			)
			(primitives
				(gr_poly
					(pts
						(arc
							(start 0.3048 -0.2032)
							(mid 0.275042 -0.275042)
							(end 0.2032 -0.3048)
						)
						(arc
							(start -0.2032 -0.3048)
							(mid -0.275042 -0.275042)
							(end -0.3048 -0.2032)
						)
						(arc
							(start -0.3048 0.2032)
							(mid -0.275042 0.275042)
							(end -0.2032 0.3048)
						)
						(arc
							(start 0.2032 0.3048)
							(mid 0.275042 0.275042)
							(end 0.3048 0.2032)
						)
					)
					(width 0)
					(fill yes)
				)
			)
		)
	)
	(footprint ""
		(layer "F.Cu")
		(at 68.8848 -171.2976 180)
		(property "Reference" "R332"
			(at 0 0 180)
			(layer "F.SilkS")
			(hide yes)
			(effects
				(font
					(size 1.27 1.27)
				)
			)
		)
		(property "Value" "4K7R2F-GP"
			(at 0.064008 -3.993896 180)
			(unlocked yes)
			(layer "F.Fab")
			(hide yes)
			(effects
				(font
					(size 1.016 1.016)
					(thickness 0.1524)
				)
			)
		)
		(property "Device Type" "R402H16"
			(at 0.064008 -5.517896 180)
			(unlocked yes)
			(layer "F.Fab")
			(hide yes)
			(effects
				(font
					(size 1.016 1.016)
					(thickness 0.1524)
				)
			)
		)
		(duplicate_pad_numbers_are_jumpers no)
		(fp_line
			(start 0.508 -0.9398)
			(end -0.508 -0.9398)
			(stroke
				(width 0.1524)
				(type default)
			)
			(layer "F.SilkS")
		)
		(fp_line
			(start -0.508 -0.9398)
			(end -0.508 0.9398)
			(stroke
				(width 0.1524)
				(type default)
			)
			(layer "F.SilkS")
		)
		(fp_rect
			(start -0.508 0.9398)
			(end 0.508 -0.9398)
			(stroke
				(width 0)
				(type default)
			)
			(fill no)
			(layer "F.CrtYd")
		)
		(fp_rect
			(start -0.508 0.9398)
			(end 0.508 -0.9398)
			(stroke
				(width 0)
				(type default)
			)
			(fill no)
			(layer "F.Fab")
		)
		(pad "1" smd custom
			(at 0 -0.4445 180)
			(size 0.1397 0.1397)
			(layers "F.Cu" "F.Mask" "F.Paste")
			(net "P3V3_STBY")
			(options
				(clearance outline)
				(anchor circle)
			)
			(primitives
				(gr_poly
					(pts
						(arc
							(start -0.1778 -0.2794)
							(mid -0.249642 -0.249642)
							(end -0.2794 -0.1778)
						)
						(arc
							(start -0.2794 0.1778)
							(mid -0.249642 0.249642)
							(end -0.1778 0.2794)
						)
						(arc
							(start 0.1778 0.2794)
							(mid 0.249642 0.249642)
							(end 0.2794 0.1778)
						)
						(arc
							(start 0.2794 -0.1778)
							(mid 0.249642 -0.249642)
							(end 0.1778 -0.2794)
						)
					)
					(width 0)
					(fill yes)
				)
			)
		)
		(pad "2" smd custom
			(at 0 0.4445 180)
			(size 0.1397 0.1397)
			(layers "F.Cu" "F.Mask" "F.Paste")
			(net "COMP_TO_BMC_RESET_N_OUT")
			(options
				(clearance outline)
				(anchor circle)
			)
			(primitives
				(gr_poly
					(pts
						(arc
							(start -0.1778 -0.2794)
							(mid -0.249642 -0.249642)
							(end -0.2794 -0.1778)
						)
						(arc
							(start -0.2794 0.1778)
							(mid -0.249642 0.249642)
							(end -0.1778 0.2794)
						)
						(arc
							(start 0.1778 0.2794)
							(mid 0.249642 0.249642)
							(end 0.2794 0.1778)
						)
						(arc
							(start 0.2794 -0.1778)
							(mid 0.249642 -0.249642)
							(end 0.1778 -0.2794)
						)
					)
					(width 0)
					(fill yes)
				)
			)
		)
	)
	(footprint ""
		(layer "F.Cu")
		(at 92.623894 -164.807646 180)
		(property "Reference" "X1"
			(at 0 0 180)
			(layer "F.SilkS")
			(hide yes)
			(effects
				(font
					(size 1.27 1.27)
				)
			)
		)
		(property "Value" "XTAL-24MHZ-87-GP"
			(at -0.0889 -3.0988 180)
			(unlocked yes)
			(layer "F.Fab")
			(hide yes)
			(effects
				(font
					(size 1.016 1.016)
					(thickness 0.1524)
				)
			)
		)
		(property "Device Type" "OSC-3225-4P-4H30"
			(at -0.0889 -4.6228 180)
			(unlocked yes)
			(layer "F.Fab")
			(hide yes)
			(effects
				(font
					(size 1.016 1.016)
					(thickness 0.1524)
				)
			)
		)
		(duplicate_pad_numbers_are_jumpers no)
		(fp_line
			(start 2.1209 1.5494)
			(end 2.1209 -1.5494)
			(stroke
				(width 0.1524)
				(type default)
			)
			(layer "F.SilkS")
		)
		(fp_line
			(start 2.1209 -1.5494)
			(end -2.1209 -1.5494)
			(stroke
				(width 0.1524)
				(type default)
			)
			(layer "F.SilkS")
		)
		(fp_line
			(start -1.143 1.651)
			(end -2.2098 1.651)
			(stroke
				(width 0.3302)
				(type default)
			)
			(layer "F.SilkS")
		)
		(fp_line
			(start -2.1209 1.5494)
			(end 2.1209 1.5494)
			(stroke
				(width 0.1524)
				(type default)
			)
			(layer "F.SilkS")
		)
		(fp_line
			(start -2.1209 -1.5494)
			(end -2.1209 1.5494)
			(stroke
				(width 0.1524)
				(type default)
			)
			(layer "F.SilkS")
		)
		(fp_line
			(start -2.2098 1.651)
			(end -2.2098 0.6604)
			(stroke
				(width 0.3302)
				(type default)
			)
			(layer "F.SilkS")
		)
		(fp_poly
			(pts
				(xy -2.6289 1.1938) (xy -2.6289 0.3302) (xy -2.1971 0.762)
			)
			(stroke
				(width 0)
				(type default)
			)
			(fill yes)
			(layer "F.SilkS")
		)
		(fp_rect
			(start -1.6002 1.2446)
			(end 1.6002 -1.2446)
			(stroke
				(width 0)
				(type default)
			)
			(fill no)
			(layer "F.CrtYd")
		)
		(fp_poly
			(pts
				(xy -2.3749 1.8034) (xy -2.3749 -1.8034) (xy 2.3749 -1.8034) (xy 2.3749 1.8034) (xy 0.00254 1.8034)
				(xy 0.00254 1.2446) (xy 1.6002 1.2446) (xy 1.6002 -1.2446) (xy -1.6002 -1.2446) (xy -1.6002 1.2446)
				(xy -0.00254 1.2446) (xy -0.00254 1.8034)
			)
			(stroke
				(width 0)
				(type default)
			)
			(fill no)
			(layer "F.CrtYd")
		)
		(fp_rect
			(start -2.3749 1.8034)
			(end 2.3749 -1.8034)
			(stroke
				(width 0)
				(type default)
			)
			(fill no)
			(layer "F.Fab")
		)
		(pad "1" smd rect
			(at -1.171448 0.756412 180)
			(size 1.397 1.0668)
			(layers "F.Cu" "F.Mask" "F.Paste")
			(net "USB_HUB_XTAL_OUT")
		)
		(pad "2" smd rect
			(at 1.171448 0.756412 180)
			(size 1.397 1.0668)
			(layers "F.Cu" "F.Mask" "F.Paste")
			(net "GND")
		)
		(pad "3" smd rect
			(at 1.171448 -0.756412 180)
			(size 1.397 1.0668)
			(layers "F.Cu" "F.Mask" "F.Paste")
			(net "USB_HUB_XTAL_IN")
		)
		(pad "4" smd rect
			(at -1.171448 -0.756412 180)
			(size 1.397 1.0668)
			(layers "F.Cu" "F.Mask" "F.Paste")
			(net "GND")
		)
		(zone
			(layer "F.Cu")
			(hatch none 0.5)
			(connect_pads
				(clearance 0)
			)
			(min_thickness 0.25)
			(keepout
				(tracks not_allowed)
				(vias allowed)
				(pads allowed)
				(copperpour not_allowed)
				(footprints allowed)
			)
			(placement
				(enabled no)
				(sheetname "")
			)
			(fill
				(thermal_gap 0.5)
				(thermal_bridge_width 0.5)
				(island_removal_mode 0)
			)
			(polygon
				(pts
					(xy 92.674694 -164.858446) (xy 92.573094 -164.858446) (xy 92.573094 -164.756846) (xy 92.674694 -164.756846)
				)
			)
		)
		(zone
			(layer "F.Cu")
			(hatch none 0.5)
			(connect_pads
				(clearance 0)
			)
			(min_thickness 0.25)
			(keepout
				(tracks allowed)
				(vias not_allowed)
				(pads allowed)
				(copperpour not_allowed)
				(footprints allowed)
			)
			(placement
				(enabled no)
				(sheetname "")
			)
			(fill
				(thermal_gap 0.5)
				(thermal_bridge_width 0.5)
				(island_removal_mode 0)
			)
			(polygon
				(pts
					(xy 93.096842 -163.517834) (xy 92.150946 -163.517834) (xy 92.150946 -164.584634) (xy 90.753946 -164.584634)
					(xy 90.753946 -165.030658) (xy 92.150946 -165.030658) (xy 92.150946 -166.097458) (xy 93.096842 -166.097458)
					(xy 93.096842 -165.030658) (xy 94.493842 -165.030658) (xy 94.493842 -164.584634) (xy 93.096842 -164.584634)
				)
			)
		)
	)
)
